# S9S_MB_2U (Grand Teton) — schematic netlist excerpt (pin names and nets, part order shuffled) for the footprints in the layout excerpt that follows; sources: Cadence DE-HDL packaged netlist, KiCad conversion of 03242023_DA0F0TMBIJ0_F0T_Motherboard_J_brd_V01_OCP.brd

R4652  Q_RES  0 5% EMPTY  pkg 0402LF  page 306 : A = A_HSC_LOW_DRAIN ; B = HSC_D_OC
C1023  Q_CAP  22UF 4V 20% X6S  pkg C0402  page 74 : A = PVCCIN_CPU0 ; B = GND

(kicad_pcb
	(version 20260206)
	(generator "pcbnew")
	(generator_version "10.0")
	(general
		(thickness 1.6)
		(legacy_teardrops no)
	)
	(paper "A4")
	(title_block
		(title "03242023_DA0F0TMBIJ0_F0T_Motherboard_J_brd_V01_OCP.brd")
		(comment 1 "Grand Teton / footprints 3708-3709 of 6105")
	)
	(layers
		(0 "F.Cu" signal "TOP")
		(4 "In1.Cu" signal "GND")
		(6 "In2.Cu" signal "IN1")
		(8 "In3.Cu" signal "GND1")
		(10 "In4.Cu" signal "IN2")
		(12 "In5.Cu" signal "GND2")
		(14 "In6.Cu" signal "IN3")
		(16 "In7.Cu" signal "GND3")
		(18 "In8.Cu" signal "VCC")
		(20 "In9.Cu" signal "VCC1")
		(22 "In10.Cu" signal "GND4")
		(24 "In11.Cu" signal "IN4")
		(26 "In12.Cu" signal "GND5")
		(28 "In13.Cu" signal "IN5")
		(30 "In14.Cu" signal "GND6")
		(32 "In15.Cu" signal "IN6")
		(34 "In16.Cu" signal "GND7")
		(2 "B.Cu" signal "BOTTOM")
		(9 "F.Adhes" user "F.Adhesive")
		(11 "B.Adhes" user "B.Adhesive")
		(13 "F.Paste" user "Package Geometry/Pastemask Top")
		(15 "B.Paste" user "Package Geometry/Pastemask Bottom")
		(5 "F.SilkS" user "Ref Des/Silkscreen Top")
		(7 "B.SilkS" user "Ref Des/Silkscreen Bottom")
		(1 "F.Mask" user "Board Geometry/Soldermask Top")
		(3 "B.Mask" user "Board Geometry/Soldermask Bottom")
		(17 "Dwgs.User" user "User.Drawings")
		(19 "Cmts.User" user "User.Comments")
		(21 "Eco1.User" user "User.Eco1")
		(23 "Eco2.User" user "User.Eco2")
		(25 "Edge.Cuts" user "Board Geometry/Outline")
		(27 "Margin" user)
		(31 "F.CrtYd" user "Package Geometry/Place Bound Top")
		(29 "B.CrtYd" user "Package Geometry/Place Bound Bottom")
		(35 "F.Fab" user "Ref Des/Assembly Top")
		(33 "B.Fab" user "Ref Des/Assembly Bottom")
	)
	(footprint ""
		(layer "F.Cu")
		(at 273.801078 -422.6433)
		(property "Reference" "R4652"
			(at 0 0 0)
			(layer "F.SilkS")
			(hide yes)
			(effects
				(font
					(size 1.27 1.27)
				)
			)
		)
		(property "Value" ""
			(at 0 0 0)
			(layer "F.Fab")
			(effects
				(font
					(size 1.27 1.27)
				)
			)
		)
		(duplicate_pad_numbers_are_jumpers no)
		(fp_line
			(start -0.7874 -0.4064)
			(end 0.7874 -0.4064)
			(stroke
				(width 0.1524)
				(type default)
			)
			(layer "F.SilkS")
		)
		(fp_line
			(start -0.7874 0.4064)
			(end -0.7874 -0.4064)
			(stroke
				(width 0.1524)
				(type default)
			)
			(layer "F.SilkS")
		)
		(fp_line
			(start 0.7874 -0.4064)
			(end 0.7874 0.4064)
			(stroke
				(width 0.1524)
				(type default)
			)
			(layer "F.SilkS")
		)
		(fp_line
			(start 0.7874 0.4064)
			(end -0.7874 0.4064)
			(stroke
				(width 0.1524)
				(type default)
			)
			(layer "F.SilkS")
		)
		(fp_line
			(start -0.67945 -0.305054)
			(end -0.12065 -0.305054)
			(stroke
				(width 0.1)
				(type default)
			)
			(layer "F.Fab")
		)
		(fp_line
			(start -0.67945 0.3048)
			(end -0.67945 -0.305054)
			(stroke
				(width 0.1)
				(type default)
			)
			(layer "F.Fab")
		)
		(fp_line
			(start -0.12065 -0.305054)
			(end -0.12065 -0.2794)
			(stroke
				(width 0.1)
				(type default)
			)
			(layer "F.Fab")
		)
		(fp_line
			(start -0.12065 -0.2794)
			(end 0.12065 -0.2794)
			(stroke
				(width 0.1)
				(type default)
			)
			(layer "F.Fab")
		)
		(fp_line
			(start -0.12065 0.2794)
			(end -0.12065 0.3048)
			(stroke
				(width 0.1)
				(type default)
			)
			(layer "F.Fab")
		)
		(fp_line
			(start -0.12065 0.3048)
			(end -0.67945 0.3048)
			(stroke
				(width 0.1)
				(type default)
			)
			(layer "F.Fab")
		)
		(fp_line
			(start 0.120396 0.2794)
			(end -0.12065 0.2794)
			(stroke
				(width 0.1)
				(type default)
			)
			(layer "F.Fab")
		)
		(fp_line
			(start 0.120396 0.3048)
			(end 0.120396 0.2794)
			(stroke
				(width 0.1)
				(type default)
			)
			(layer "F.Fab")
		)
		(fp_line
			(start 0.12065 -0.3048)
			(end 0.67945 -0.3048)
			(stroke
				(width 0.1)
				(type default)
			)
			(layer "F.Fab")
		)
		(fp_line
			(start 0.12065 -0.2794)
			(end 0.12065 -0.3048)
			(stroke
				(width 0.1)
				(type default)
			)
			(layer "F.Fab")
		)
		(fp_line
			(start 0.67945 -0.3048)
			(end 0.67945 0.3048)
			(stroke
				(width 0.1)
				(type default)
			)
			(layer "F.Fab")
		)
		(fp_line
			(start 0.67945 0.3048)
			(end 0.120396 0.3048)
			(stroke
				(width 0.1)
				(type default)
			)
			(layer "F.Fab")
		)
		(pad "1" smd circle
			(at -0.40005 0)
			(size 0 0)
			(layers "F.Cu" "F.Mask" "F.Paste")
			(net "A_HSC_LOW_DRAIN")
		)
		(pad "2" smd circle
			(at 0.40005 0)
			(size 0 0)
			(layers "F.Cu" "F.Mask" "F.Paste")
			(net "HSC_D_OC")
		)
	)
	(footprint ""
		(layer "F.Cu")
		(at 355.228144 -241.976656 -90)
		(property "Reference" "C1023"
			(at 0 0 270)
			(layer "F.SilkS")
			(hide yes)
			(effects
				(font
					(size 1.27 1.27)
				)
			)
		)
		(property "Value" ""
			(at 0 0 270)
			(layer "F.Fab")
			(effects
				(font
					(size 1.27 1.27)
				)
			)
		)
		(duplicate_pad_numbers_are_jumpers no)
		(fp_line
			(start -0.7874 0.4064)
			(end -0.7874 -0.4064)
			(stroke
				(width 0.1524)
				(type default)
			)
			(layer "F.SilkS")
		)
		(fp_line
			(start 0.7874 0.4064)
			(end -0.7874 0.4064)
			(stroke
				(width 0.1524)
				(type default)
			)
			(layer "F.SilkS")
		)
		(fp_line
			(start -0.7874 -0.4064)
			(end 0.7874 -0.4064)
			(stroke
				(width 0.1524)
				(type default)
			)
			(layer "F.SilkS")
		)
		(fp_line
			(start 0.7874 -0.4064)
			(end 0.7874 0.4064)
			(stroke
				(width 0.1524)
				(type default)
			)
			(layer "F.SilkS")
		)
		(fp_line
			(start -0.67945 0.3048)
			(end -0.67945 -0.305054)
			(stroke
				(width 0.1)
				(type default)
			)
			(layer "F.Fab")
		)
		(fp_line
			(start -0.12065 0.3048)
			(end -0.67945 0.3048)
			(stroke
				(width 0.1)
				(type default)
			)
			(layer "F.Fab")
		)
		(fp_line
			(start 0.120396 0.3048)
			(end 0.120396 0.2794)
			(stroke
				(width 0.1)
				(type default)
			)
			(layer "F.Fab")
		)
		(fp_line
			(start 0.67945 0.3048)
			(end 0.120396 0.3048)
			(stroke
				(width 0.1)
				(type default)
			)
			(layer "F.Fab")
		)
		(fp_line
			(start -0.12065 0.2794)
			(end -0.12065 0.3048)
			(stroke
				(width 0.1)
				(type default)
			)
			(layer "F.Fab")
		)
		(fp_line
			(start 0.120396 0.2794)
			(end -0.12065 0.2794)
			(stroke
				(width 0.1)
				(type default)
			)
			(layer "F.Fab")
		)
		(fp_line
			(start -0.12065 -0.2794)
			(end 0.12065 -0.2794)
			(stroke
				(width 0.1)
				(type default)
			)
			(layer "F.Fab")
		)
		(fp_line
			(start 0.12065 -0.2794)
			(end 0.12065 -0.3048)
			(stroke
				(width 0.1)
				(type default)
			)
			(layer "F.Fab")
		)
		(fp_line
			(start 0.12065 -0.3048)
			(end 0.67945 -0.3048)
			(stroke
				(width 0.1)
				(type default)
			)
			(layer "F.Fab")
		)
		(fp_line
			(start 0.67945 -0.3048)
			(end 0.67945 0.3048)
			(stroke
				(width 0.1)
				(type default)
			)
			(layer "F.Fab")
		)
		(fp_line
			(start -0.67945 -0.305054)
			(end -0.12065 -0.305054)
			(stroke
				(width 0.1)
				(type default)
			)
			(layer "F.Fab")
		)
		(fp_line
			(start -0.12065 -0.305054)
			(end -0.12065 -0.2794)
			(stroke
				(width 0.1)
				(type default)
			)
			(layer "F.Fab")
		)
		(pad "1" smd circle
			(at -0.40005 0 270)
			(size 0 0)
			(layers "F.Cu" "F.Mask" "F.Paste")
			(net "PVCCIN_CPU0")
		)
		(pad "2" smd circle
			(at 0.40005 0 270)
			(size 0 0)
			(layers "F.Cu" "F.Mask" "F.Paste")
			(net "GND")
		)
	)
)
